(kicad_pcb
	(version 20260206)
	(generator "pcbnew")
	(generator_version "10.0")
	(general
		(thickness 1.6)
		(legacy_teardrops no)
	)
	(paper "A4")
	(title_block
		(title "01162023_DA0F0TEBIF0_F0T_Expander_BD_F_brd_V02_OCP.brd")
		(comment 1 "Grand Teton / footprints 555-560 of 9728")
	)
	(layers
		(0 "F.Cu" signal "TOP")
		(4 "In1.Cu" signal "GND")
		(6 "In2.Cu" signal "VCC")
		(8 "In3.Cu" signal "VCC1")
		(10 "In4.Cu" signal "GND1")
		(12 "In5.Cu" signal "IN1")
		(14 "In6.Cu" signal "GND2")
		(16 "In7.Cu" signal "IN2")
		(18 "In8.Cu" signal "GND3")
		(20 "In9.Cu" signal "IN3")
		(22 "In10.Cu" signal "GND4")
		(24 "In11.Cu" signal "IN4")
		(26 "In12.Cu" signal "GND5")
		(28 "In13.Cu" signal "IN5")
		(30 "In14.Cu" signal "GND6")
		(32 "In15.Cu" signal "IN6")
		(34 "In16.Cu" signal "GND7")
		(2 "B.Cu" signal "BOTTOM")
		(9 "F.Adhes" user "F.Adhesive")
		(11 "B.Adhes" user "B.Adhesive")
		(13 "F.Paste" user "Package Geometry/Pastemask Top")
		(15 "B.Paste" user "Package Geometry/Pastemask Bottom")
		(5 "F.SilkS" user "Ref Des/Silkscreen Top")
		(7 "B.SilkS" user "Ref Des/Silkscreen Bottom")
		(1 "F.Mask" user "Board Geometry/Soldermask Top")
		(3 "B.Mask" user "Board Geometry/Soldermask Bottom")
		(17 "Dwgs.User" user "User.Drawings")
		(19 "Cmts.User" user "User.Comments")
		(21 "Eco1.User" user "User.Eco1")
		(23 "Eco2.User" user "User.Eco2")
		(25 "Edge.Cuts" user "Board Geometry/Outline")
		(27 "Margin" user)
		(31 "F.CrtYd" user "Package Geometry/Place Bound Top")
		(29 "B.CrtYd" user "Package Geometry/Place Bound Bottom")
		(35 "F.Fab" user "Ref Des/Assembly Top")
		(33 "B.Fab" user "Ref Des/Assembly Bottom")
	)
	(footprint ""
		(layer "F.Cu")
		(at 369.830604 -66.32194 -90)
		(property "Reference" "PC884"
			(at 0 0 270)
			(layer "F.SilkS")
			(hide yes)
			(effects
				(font
					(size 1.27 1.27)
				)
			)
		)
		(property "Value" ""
			(at 0 0 270)
			(layer "F.Fab")
			(effects
				(font
					(size 1.27 1.27)
				)
			)
		)
		(duplicate_pad_numbers_are_jumpers no)
		(fp_line
			(start -0.7874 0.4064)
			(end -0.7874 -0.4064)
			(stroke
				(width 0.1524)
				(type default)
			)
			(layer "F.SilkS")
		)
		(fp_line
			(start 0.7874 0.4064)
			(end -0.7874 0.4064)
			(stroke
				(width 0.1524)
				(type default)
			)
			(layer "F.SilkS")
		)
		(fp_line
			(start -0.7874 -0.4064)
			(end 0.7874 -0.4064)
			(stroke
				(width 0.1524)
				(type default)
			)
			(layer "F.SilkS")
		)
		(fp_line
			(start 0.7874 -0.4064)
			(end 0.7874 0.4064)
			(stroke
				(width 0.1524)
				(type default)
			)
			(layer "F.SilkS")
		)
		(fp_line
			(start -0.67945 0.3048)
			(end -0.67945 -0.305054)
			(stroke
				(width 0.1)
				(type default)
			)
			(layer "F.Fab")
		)
		(fp_line
			(start -0.12065 0.3048)
			(end -0.67945 0.3048)
			(stroke
				(width 0.1)
				(type default)
			)
			(layer "F.Fab")
		)
		(fp_line
			(start 0.120396 0.3048)
			(end 0.120396 0.2794)
			(stroke
				(width 0.1)
				(type default)
			)
			(layer "F.Fab")
		)
		(fp_line
			(start 0.67945 0.3048)
			(end 0.120396 0.3048)
			(stroke
				(width 0.1)
				(type default)
			)
			(layer "F.Fab")
		)
		(fp_line
			(start -0.12065 0.2794)
			(end -0.12065 0.3048)
			(stroke
				(width 0.1)
				(type default)
			)
			(layer "F.Fab")
		)
		(fp_line
			(start 0.120396 0.2794)
			(end -0.12065 0.2794)
			(stroke
				(width 0.1)
				(type default)
			)
			(layer "F.Fab")
		)
		(fp_line
			(start -0.12065 -0.2794)
			(end 0.12065 -0.2794)
			(stroke
				(width 0.1)
				(type default)
			)
			(layer "F.Fab")
		)
		(fp_line
			(start 0.12065 -0.2794)
			(end 0.12065 -0.3048)
			(stroke
				(width 0.1)
				(type default)
			)
			(layer "F.Fab")
		)
		(fp_line
			(start 0.12065 -0.3048)
			(end 0.67945 -0.3048)
			(stroke
				(width 0.1)
				(type default)
			)
			(layer "F.Fab")
		)
		(fp_line
			(start 0.67945 -0.3048)
			(end 0.67945 0.3048)
			(stroke
				(width 0.1)
				(type default)
			)
			(layer "F.Fab")
		)
		(fp_line
			(start -0.67945 -0.305054)
			(end -0.12065 -0.305054)
			(stroke
				(width 0.1)
				(type default)
			)
			(layer "F.Fab")
		)
		(fp_line
			(start -0.12065 -0.305054)
			(end -0.12065 -0.2794)
			(stroke
				(width 0.1)
				(type default)
			)
			(layer "F.Fab")
		)
		(pad "1" smd circle
			(at -0.40005 0 270)
			(size 0 0)
			(layers "F.Cu" "F.Mask" "F.Paste")
			(net "P12V_SSD12_CO_DV_DT")
		)
		(pad "2" smd circle
			(at 0.40005 0 270)
			(size 0 0)
			(layers "F.Cu" "F.Mask" "F.Paste")
			(net "GND")
		)
	)
	(footprint ""
		(layer "F.Cu")
		(at 277.726648 -55.418228 90)
		(property "Reference" "PC416"
			(at 0 0 90)
			(layer "F.SilkS")
			(hide yes)
			(effects
				(font
					(size 1.27 1.27)
				)
			)
		)
		(property "Value" ""
			(at 0 0 90)
			(layer "F.Fab")
			(effects
				(font
					(size 1.27 1.27)
				)
			)
		)
		(duplicate_pad_numbers_are_jumpers no)
		(fp_line
			(start 0.7874 -0.4064)
			(end 0.7874 0.4064)
			(stroke
				(width 0.1524)
				(type default)
			)
			(layer "F.SilkS")
		)
		(fp_line
			(start -0.7874 -0.4064)
			(end 0.7874 -0.4064)
			(stroke
				(width 0.1524)
				(type default)
			)
			(layer "F.SilkS")
		)
		(fp_line
			(start 0.7874 0.4064)
			(end -0.7874 0.4064)
			(stroke
				(width 0.1524)
				(type default)
			)
			(layer "F.SilkS")
		)
		(fp_line
			(start -0.7874 0.4064)
			(end -0.7874 -0.4064)
			(stroke
				(width 0.1524)
				(type default)
			)
			(layer "F.SilkS")
		)
		(fp_line
			(start -0.12065 -0.305054)
			(end -0.12065 -0.2794)
			(stroke
				(width 0.1)
				(type default)
			)
			(layer "F.Fab")
		)
		(fp_line
			(start -0.67945 -0.305054)
			(end -0.12065 -0.305054)
			(stroke
				(width 0.1)
				(type default)
			)
			(layer "F.Fab")
		)
		(fp_line
			(start 0.67945 -0.3048)
			(end 0.67945 0.3048)
			(stroke
				(width 0.1)
				(type default)
			)
			(layer "F.Fab")
		)
		(fp_line
			(start 0.12065 -0.3048)
			(end 0.67945 -0.3048)
			(stroke
				(width 0.1)
				(type default)
			)
			(layer "F.Fab")
		)
		(fp_line
			(start 0.12065 -0.2794)
			(end 0.12065 -0.3048)
			(stroke
				(width 0.1)
				(type default)
			)
			(layer "F.Fab")
		)
		(fp_line
			(start -0.12065 -0.2794)
			(end 0.12065 -0.2794)
			(stroke
				(width 0.1)
				(type default)
			)
			(layer "F.Fab")
		)
		(fp_line
			(start 0.120396 0.2794)
			(end -0.12065 0.2794)
			(stroke
				(width 0.1)
				(type default)
			)
			(layer "F.Fab")
		)
		(fp_line
			(start -0.12065 0.2794)
			(end -0.12065 0.3048)
			(stroke
				(width 0.1)
				(type default)
			)
			(layer "F.Fab")
		)
		(fp_line
			(start 0.67945 0.3048)
			(end 0.120396 0.3048)
			(stroke
				(width 0.1)
				(type default)
			)
			(layer "F.Fab")
		)
		(fp_line
			(start 0.120396 0.3048)
			(end 0.120396 0.2794)
			(stroke
				(width 0.1)
				(type default)
			)
			(layer "F.Fab")
		)
		(fp_line
			(start -0.12065 0.3048)
			(end -0.67945 0.3048)
			(stroke
				(width 0.1)
				(type default)
			)
			(layer "F.Fab")
		)
		(fp_line
			(start -0.67945 0.3048)
			(end -0.67945 -0.305054)
			(stroke
				(width 0.1)
				(type default)
			)
			(layer "F.Fab")
		)
		(pad "1" smd circle
			(at -0.40005 0 90)
			(size 0 0)
			(layers "F.Cu" "F.Mask" "F.Paste")
			(net "P12V_SSD9_R")
		)
		(pad "2" smd circle
			(at 0.40005 0 90)
			(size 0 0)
			(layers "F.Cu" "F.Mask" "F.Paste")
			(net "GND")
		)
	)
	(footprint ""
		(layer "F.Cu")
		(at 323.233542 -304.036476 90)
		(property "Reference" "R1386"
			(at 0 0 90)
			(layer "F.SilkS")
			(hide yes)
			(effects
				(font
					(size 1.27 1.27)
				)
			)
		)
		(property "Value" ""
			(at 0 0 90)
			(layer "F.Fab")
			(effects
				(font
					(size 1.27 1.27)
				)
			)
		)
		(duplicate_pad_numbers_are_jumpers no)
		(fp_line
			(start 0.7874 -0.4064)
			(end 0.7874 0.4064)
			(stroke
				(width 0.1524)
				(type default)
			)
			(layer "F.SilkS")
		)
		(fp_line
			(start -0.7874 -0.4064)
			(end 0.7874 -0.4064)
			(stroke
				(width 0.1524)
				(type default)
			)
			(layer "F.SilkS")
		)
		(fp_line
			(start 0.7874 0.4064)
			(end -0.7874 0.4064)
			(stroke
				(width 0.1524)
				(type default)
			)
			(layer "F.SilkS")
		)
		(fp_line
			(start -0.7874 0.4064)
			(end -0.7874 -0.4064)
			(stroke
				(width 0.1524)
				(type default)
			)
			(layer "F.SilkS")
		)
		(fp_line
			(start -0.12065 -0.305054)
			(end -0.12065 -0.2794)
			(stroke
				(width 0.1)
				(type default)
			)
			(layer "F.Fab")
		)
		(fp_line
			(start -0.67945 -0.305054)
			(end -0.12065 -0.305054)
			(stroke
				(width 0.1)
				(type default)
			)
			(layer "F.Fab")
		)
		(fp_line
			(start 0.67945 -0.3048)
			(end 0.67945 0.3048)
			(stroke
				(width 0.1)
				(type default)
			)
			(layer "F.Fab")
		)
		(fp_line
			(start 0.12065 -0.3048)
			(end 0.67945 -0.3048)
			(stroke
				(width 0.1)
				(type default)
			)
			(layer "F.Fab")
		)
		(fp_line
			(start 0.12065 -0.2794)
			(end 0.12065 -0.3048)
			(stroke
				(width 0.1)
				(type default)
			)
			(layer "F.Fab")
		)
		(fp_line
			(start -0.12065 -0.2794)
			(end 0.12065 -0.2794)
			(stroke
				(width 0.1)
				(type default)
			)
			(layer "F.Fab")
		)
		(fp_line
			(start 0.120396 0.2794)
			(end -0.12065 0.2794)
			(stroke
				(width 0.1)
				(type default)
			)
			(layer "F.Fab")
		)
		(fp_line
			(start -0.12065 0.2794)
			(end -0.12065 0.3048)
			(stroke
				(width 0.1)
				(type default)
			)
			(layer "F.Fab")
		)
		(fp_line
			(start 0.67945 0.3048)
			(end 0.120396 0.3048)
			(stroke
				(width 0.1)
				(type default)
			)
			(layer "F.Fab")
		)
		(fp_line
			(start 0.120396 0.3048)
			(end 0.120396 0.2794)
			(stroke
				(width 0.1)
				(type default)
			)
			(layer "F.Fab")
		)
		(fp_line
			(start -0.12065 0.3048)
			(end -0.67945 0.3048)
			(stroke
				(width 0.1)
				(type default)
			)
			(layer "F.Fab")
		)
		(fp_line
			(start -0.67945 0.3048)
			(end -0.67945 -0.305054)
			(stroke
				(width 0.1)
				(type default)
			)
			(layer "F.Fab")
		)
		(pad "1" smd circle
			(at -0.40005 0 90)
			(size 0 0)
			(layers "F.Cu" "F.Mask" "F.Paste")
			(net "GND")
		)
		(pad "2" smd circle
			(at 0.40005 0 90)
			(size 0 0)
			(layers "F.Cu" "F.Mask" "F.Paste")
			(net "PEX2_SPARE1")
		)
	)
	(footprint ""
		(layer "F.Cu")
		(at 220.34373 -42.84091)
		(property "Reference" "R582"
			(at 0 0 0)
			(layer "F.SilkS")
			(hide yes)
			(effects
				(font
					(size 1.27 1.27)
				)
			)
		)
		(property "Value" ""
			(at 0 0 0)
			(layer "F.Fab")
			(effects
				(font
					(size 1.27 1.27)
				)
			)
		)
		(duplicate_pad_numbers_are_jumpers no)
		(fp_line
			(start -0.7874 -0.4064)
			(end 0.7874 -0.4064)
			(stroke
				(width 0.1524)
				(type default)
			)
			(layer "F.SilkS")
		)
		(fp_line
			(start -0.7874 0.4064)
			(end -0.7874 -0.4064)
			(stroke
				(width 0.1524)
				(type default)
			)
			(layer "F.SilkS")
		)
		(fp_line
			(start 0.7874 -0.4064)
			(end 0.7874 0.4064)
			(stroke
				(width 0.1524)
				(type default)
			)
			(layer "F.SilkS")
		)
		(fp_line
			(start 0.7874 0.4064)
			(end -0.7874 0.4064)
			(stroke
				(width 0.1524)
				(type default)
			)
			(layer "F.SilkS")
		)
		(fp_line
			(start -0.67945 -0.305054)
			(end -0.12065 -0.305054)
			(stroke
				(width 0.1)
				(type default)
			)
			(layer "F.Fab")
		)
		(fp_line
			(start -0.67945 0.3048)
			(end -0.67945 -0.305054)
			(stroke
				(width 0.1)
				(type default)
			)
			(layer "F.Fab")
		)
		(fp_line
			(start -0.12065 -0.305054)
			(end -0.12065 -0.2794)
			(stroke
				(width 0.1)
				(type default)
			)
			(layer "F.Fab")
		)
		(fp_line
			(start -0.12065 -0.2794)
			(end 0.12065 -0.2794)
			(stroke
				(width 0.1)
				(type default)
			)
			(layer "F.Fab")
		)
		(fp_line
			(start -0.12065 0.2794)
			(end -0.12065 0.3048)
			(stroke
				(width 0.1)
				(type default)
			)
			(layer "F.Fab")
		)
		(fp_line
			(start -0.12065 0.3048)
			(end -0.67945 0.3048)
			(stroke
				(width 0.1)
				(type default)
			)
			(layer "F.Fab")
		)
		(fp_line
			(start 0.120396 0.2794)
			(end -0.12065 0.2794)
			(stroke
				(width 0.1)
				(type default)
			)
			(layer "F.Fab")
		)
		(fp_line
			(start 0.120396 0.3048)
			(end 0.120396 0.2794)
			(stroke
				(width 0.1)
				(type default)
			)
			(layer "F.Fab")
		)
		(fp_line
			(start 0.12065 -0.3048)
			(end 0.67945 -0.3048)
			(stroke
				(width 0.1)
				(type default)
			)
			(layer "F.Fab")
		)
		(fp_line
			(start 0.12065 -0.2794)
			(end 0.12065 -0.3048)
			(stroke
				(width 0.1)
				(type default)
			)
			(layer "F.Fab")
		)
		(fp_line
			(start 0.67945 -0.3048)
			(end 0.67945 0.3048)
			(stroke
				(width 0.1)
				(type default)
			)
			(layer "F.Fab")
		)
		(fp_line
			(start 0.67945 0.3048)
			(end 0.120396 0.3048)
			(stroke
				(width 0.1)
				(type default)
			)
			(layer "F.Fab")
		)
		(pad "1" smd circle
			(at -0.40005 0)
			(size 0 0)
			(layers "F.Cu" "F.Mask" "F.Paste")
			(net "SSD7_ADC_A1")
		)
		(pad "2" smd circle
			(at 0.40005 0)
			(size 0 0)
			(layers "F.Cu" "F.Mask" "F.Paste")
			(net "P3V3_AUX")
		)
	)
	(footprint ""
		(layer "F.Cu")
		(at 26.243788 -45.88891)
		(property "Reference" "R508"
			(at 0 0 0)
			(layer "F.SilkS")
			(hide yes)
			(effects
				(font
					(size 1.27 1.27)
				)
			)
		)
		(property "Value" ""
			(at 0 0 0)
			(layer "F.Fab")
			(effects
				(font
					(size 1.27 1.27)
				)
			)
		)
		(duplicate_pad_numbers_are_jumpers no)
		(fp_line
			(start -0.7874 -0.4064)
			(end 0.7874 -0.4064)
			(stroke
				(width 0.1524)
				(type default)
			)
			(layer "F.SilkS")
		)
		(fp_line
			(start -0.7874 0.4064)
			(end -0.7874 -0.4064)
			(stroke
				(width 0.1524)
				(type default)
			)
			(layer "F.SilkS")
		)
		(fp_line
			(start 0.7874 -0.4064)
			(end 0.7874 0.4064)
			(stroke
				(width 0.1524)
				(type default)
			)
			(layer "F.SilkS")
		)
		(fp_line
			(start 0.7874 0.4064)
			(end -0.7874 0.4064)
			(stroke
				(width 0.1524)
				(type default)
			)
			(layer "F.SilkS")
		)
		(fp_line
			(start -0.67945 -0.305054)
			(end -0.12065 -0.305054)
			(stroke
				(width 0.1)
				(type default)
			)
			(layer "F.Fab")
		)
		(fp_line
			(start -0.67945 0.3048)
			(end -0.67945 -0.305054)
			(stroke
				(width 0.1)
				(type default)
			)
			(layer "F.Fab")
		)
		(fp_line
			(start -0.12065 -0.305054)
			(end -0.12065 -0.2794)
			(stroke
				(width 0.1)
				(type default)
			)
			(layer "F.Fab")
		)
		(fp_line
			(start -0.12065 -0.2794)
			(end 0.12065 -0.2794)
			(stroke
				(width 0.1)
				(type default)
			)
			(layer "F.Fab")
		)
		(fp_line
			(start -0.12065 0.2794)
			(end -0.12065 0.3048)
			(stroke
				(width 0.1)
				(type default)
			)
			(layer "F.Fab")
		)
		(fp_line
			(start -0.12065 0.3048)
			(end -0.67945 0.3048)
			(stroke
				(width 0.1)
				(type default)
			)
			(layer "F.Fab")
		)
		(fp_line
			(start 0.120396 0.2794)
			(end -0.12065 0.2794)
			(stroke
				(width 0.1)
				(type default)
			)
			(layer "F.Fab")
		)
		(fp_line
			(start 0.120396 0.3048)
			(end 0.120396 0.2794)
			(stroke
				(width 0.1)
				(type default)
			)
			(layer "F.Fab")
		)
		(fp_line
			(start 0.12065 -0.3048)
			(end 0.67945 -0.3048)
			(stroke
				(width 0.1)
				(type default)
			)
			(layer "F.Fab")
		)
		(fp_line
			(start 0.12065 -0.2794)
			(end 0.12065 -0.3048)
			(stroke
				(width 0.1)
				(type default)
			)
			(layer "F.Fab")
		)
		(fp_line
			(start 0.67945 -0.3048)
			(end 0.67945 0.3048)
			(stroke
				(width 0.1)
				(type default)
			)
			(layer "F.Fab")
		)
		(fp_line
			(start 0.67945 0.3048)
			(end 0.120396 0.3048)
			(stroke
				(width 0.1)
				(type default)
			)
			(layer "F.Fab")
		)
		(pad "1" smd circle
			(at -0.40005 0)
			(size 0 0)
			(layers "F.Cu" "F.Mask" "F.Paste")
			(net "SSD0_ADC_A0")
		)
		(pad "2" smd circle
			(at 0.40005 0)
			(size 0 0)
			(layers "F.Cu" "F.Mask" "F.Paste")
			(net "GND")
		)
	)
	(footprint ""
		(layer "F.Cu")
		(at 210.59394 -115.902486)
		(property "Reference" "PC795"
			(at 0 0 0)
			(layer "F.SilkS")
			(hide yes)
			(effects
				(font
					(size 1.27 1.27)
				)
			)
		)
		(property "Value" ""
			(at 0 0 0)
			(layer "F.Fab")
			(effects
				(font
					(size 1.27 1.27)
				)
			)
		)
		(duplicate_pad_numbers_are_jumpers no)
		(fp_line
			(start -0.7874 -0.4064)
			(end 0.7874 -0.4064)
			(stroke
				(width 0.1524)
				(type default)
			)
			(layer "F.SilkS")
		)
		(fp_line
			(start -0.7874 0.4064)
			(end -0.7874 -0.4064)
			(stroke
				(width 0.1524)
				(type default)
			)
			(layer "F.SilkS")
		)
		(fp_line
			(start 0.7874 -0.4064)
			(end 0.7874 0.4064)
			(stroke
				(width 0.1524)
				(type default)
			)
			(layer "F.SilkS")
		)
		(fp_line
			(start 0.7874 0.4064)
			(end -0.7874 0.4064)
			(stroke
				(width 0.1524)
				(type default)
			)
			(layer "F.SilkS")
		)
		(fp_line
			(start -0.67945 -0.305054)
			(end -0.12065 -0.305054)
			(stroke
				(width 0.1)
				(type default)
			)
			(layer "F.Fab")
		)
		(fp_line
			(start -0.67945 0.3048)
			(end -0.67945 -0.305054)
			(stroke
				(width 0.1)
				(type default)
			)
			(layer "F.Fab")
		)
		(fp_line
			(start -0.12065 -0.305054)
			(end -0.12065 -0.2794)
			(stroke
				(width 0.1)
				(type default)
			)
			(layer "F.Fab")
		)
		(fp_line
			(start -0.12065 -0.2794)
			(end 0.12065 -0.2794)
			(stroke
				(width 0.1)
				(type default)
			)
			(layer "F.Fab")
		)
		(fp_line
			(start -0.12065 0.2794)
			(end -0.12065 0.3048)
			(stroke
				(width 0.1)
				(type default)
			)
			(layer "F.Fab")
		)
		(fp_line
			(start -0.12065 0.3048)
			(end -0.67945 0.3048)
			(stroke
				(width 0.1)
				(type default)
			)
			(layer "F.Fab")
		)
		(fp_line
			(start 0.120396 0.2794)
			(end -0.12065 0.2794)
			(stroke
				(width 0.1)
				(type default)
			)
			(layer "F.Fab")
		)
		(fp_line
			(start 0.120396 0.3048)
			(end 0.120396 0.2794)
			(stroke
				(width 0.1)
				(type default)
			)
			(layer "F.Fab")
		)
		(fp_line
			(start 0.12065 -0.3048)
			(end 0.67945 -0.3048)
			(stroke
				(width 0.1)
				(type default)
			)
			(layer "F.Fab")
		)
		(fp_line
			(start 0.12065 -0.2794)
			(end 0.12065 -0.3048)
			(stroke
				(width 0.1)
				(type default)
			)
			(layer "F.Fab")
		)
		(fp_line
			(start 0.67945 -0.3048)
			(end 0.67945 0.3048)
			(stroke
				(width 0.1)
				(type default)
			)
			(layer "F.Fab")
		)
		(fp_line
			(start 0.67945 0.3048)
			(end 0.120396 0.3048)
			(stroke
				(width 0.1)
				(type default)
			)
			(layer "F.Fab")
		)
		(pad "1" smd circle
			(at -0.40005 0)
			(size 0 0)
			(layers "F.Cu" "F.Mask" "F.Paste")
			(net "P3V3_NIC3_CO_MODE")
		)
		(pad "2" smd circle
			(at 0.40005 0)
			(size 0 0)
			(layers "F.Cu" "F.Mask" "F.Paste")
			(net "GND")
		)
	)
)
